(kicad_pcb
	(version 20260206)
	(generator "pcbnew")
	(generator_version "10.0")
	(general
		(thickness 1.6)
		(legacy_teardrops no)
	)
	(paper "A4")
	(title_block
		(title "dpb — 14545-sa.0730WZS0815.brd")
		(comment 1 "Honey Badger (Wiwynn) / footprints 752-754 of 1066")
	)
	(layers
		(0 "F.Cu" signal "TOP")
		(4 "In1.Cu" signal "L2GND")
		(6 "In2.Cu" signal "L3")
		(8 "In3.Cu" signal "L4VCC")
		(10 "In4.Cu" signal "L5VCC")
		(12 "In5.Cu" signal "L6")
		(14 "In6.Cu" signal "L7GND")
		(2 "B.Cu" signal "BOTTOM")
		(9 "F.Adhes" user "F.Adhesive")
		(11 "B.Adhes" user "B.Adhesive")
		(13 "F.Paste" user "Package Geometry/Pastemask Top")
		(15 "B.Paste" user "Package Geometry/Pastemask Bottom")
		(5 "F.SilkS" user "Ref Des/Silkscreen Top")
		(7 "B.SilkS" user "Ref Des/Silkscreen Bottom")
		(1 "F.Mask" user "Board Geometry/Soldermask Top")
		(3 "B.Mask" user "Board Geometry/Soldermask Bottom")
		(17 "Dwgs.User" user "User.Drawings")
		(19 "Cmts.User" user "User.Comments")
		(21 "Eco1.User" user "User.Eco1")
		(23 "Eco2.User" user "User.Eco2")
		(25 "Edge.Cuts" user "Board Geometry/Outline")
		(27 "Margin" user)
		(31 "F.CrtYd" user "Package Geometry/Place Bound Top")
		(29 "B.CrtYd" user "Package Geometry/Place Bound Bottom")
		(35 "F.Fab" user "Ref Des/Assembly Top")
		(33 "B.Fab" user "Ref Des/Assembly Bottom")
	)
	(footprint ""
		(layer "F.Cu")
		(at 11.734546 -52.8066 -90)
		(property "Reference" "Q48"
			(at 0 0 270)
			(layer "F.SilkS")
			(hide yes)
			(effects
				(font
					(size 1.27 1.27)
				)
			)
		)
		(property "Value" "PMBS3904-1-GP"
			(at 0 -9.0932 270)
			(unlocked yes)
			(layer "F.Fab")
			(hide yes)
			(effects
				(font
					(size 1.016 1.016)
					(thickness 0.1524)
				)
			)
		)
		(property "Device Type" "SOT-23-10H44"
			(at 0 -10.6172 270)
			(unlocked yes)
			(layer "F.Fab")
			(hide yes)
			(effects
				(font
					(size 1.016 1.016)
					(thickness 0.1524)
				)
			)
		)
		(duplicate_pad_numbers_are_jumpers no)
		(fp_line
			(start -1.279144 2.15265)
			(end -0.701294 2.15265)
			(stroke
				(width 0.0127)
				(type default)
			)
			(layer "F.SilkS")
		)
		(fp_line
			(start -0.71628 2.15265)
			(end -1.26492 2.15265)
			(stroke
				(width 0.0127)
				(type default)
			)
			(layer "F.SilkS")
		)
		(fp_line
			(start -1.279398 2.152142)
			(end -0.9906 1.86309)
			(stroke
				(width 0.0127)
				(type default)
			)
			(layer "F.SilkS")
		)
		(fp_line
			(start -0.719074 2.145538)
			(end -1.265936 2.14122)
			(stroke
				(width 0.0127)
				(type default)
			)
			(layer "F.SilkS")
		)
		(fp_line
			(start -1.260856 2.1336)
			(end -0.720344 2.1336)
			(stroke
				(width 0.0127)
				(type default)
			)
			(layer "F.SilkS")
		)
		(fp_line
			(start -1.251458 2.124202)
			(end -0.729996 2.124202)
			(stroke
				(width 0.0127)
				(type default)
			)
			(layer "F.SilkS")
		)
		(fp_line
			(start -1.241806 2.11455)
			(end -0.739394 2.11455)
			(stroke
				(width 0.0127)
				(type default)
			)
			(layer "F.SilkS")
		)
		(fp_line
			(start -1.232408 2.105152)
			(end -0.749046 2.105152)
			(stroke
				(width 0.0127)
				(type default)
			)
			(layer "F.SilkS")
		)
		(fp_line
			(start -1.222756 2.0955)
			(end -0.758444 2.0955)
			(stroke
				(width 0.0127)
				(type default)
			)
			(layer "F.SilkS")
		)
		(fp_line
			(start -1.213358 2.086102)
			(end -0.768096 2.086102)
			(stroke
				(width 0.0127)
				(type default)
			)
			(layer "F.SilkS")
		)
		(fp_line
			(start -1.203706 2.07645)
			(end -0.777494 2.07645)
			(stroke
				(width 0.0127)
				(type default)
			)
			(layer "F.SilkS")
		)
		(fp_line
			(start -1.194308 2.067052)
			(end -0.787146 2.067052)
			(stroke
				(width 0.0127)
				(type default)
			)
			(layer "F.SilkS")
		)
		(fp_line
			(start -1.184656 2.0574)
			(end -0.796544 2.0574)
			(stroke
				(width 0.0127)
				(type default)
			)
			(layer "F.SilkS")
		)
		(fp_line
			(start -1.175258 2.048002)
			(end -0.806196 2.048002)
			(stroke
				(width 0.0127)
				(type default)
			)
			(layer "F.SilkS")
		)
		(fp_line
			(start -1.165606 2.03835)
			(end -0.815594 2.03835)
			(stroke
				(width 0.0127)
				(type default)
			)
			(layer "F.SilkS")
		)
		(fp_line
			(start -1.156208 2.028952)
			(end -0.825246 2.028952)
			(stroke
				(width 0.0127)
				(type default)
			)
			(layer "F.SilkS")
		)
		(fp_line
			(start -1.146556 2.0193)
			(end -0.834644 2.0193)
			(stroke
				(width 0.0127)
				(type default)
			)
			(layer "F.SilkS")
		)
		(fp_line
			(start -1.137158 2.009902)
			(end -0.844296 2.009902)
			(stroke
				(width 0.0127)
				(type default)
			)
			(layer "F.SilkS")
		)
		(fp_line
			(start -1.127506 2.00025)
			(end -0.853694 2.00025)
			(stroke
				(width 0.0127)
				(type default)
			)
			(layer "F.SilkS")
		)
		(fp_line
			(start -1.118108 1.990852)
			(end -0.863346 1.990852)
			(stroke
				(width 0.0127)
				(type default)
			)
			(layer "F.SilkS")
		)
		(fp_line
			(start -1.108456 1.9812)
			(end -0.872744 1.9812)
			(stroke
				(width 0.0127)
				(type default)
			)
			(layer "F.SilkS")
		)
		(fp_line
			(start -1.099058 1.971802)
			(end -0.882396 1.971802)
			(stroke
				(width 0.0127)
				(type default)
			)
			(layer "F.SilkS")
		)
		(fp_line
			(start -1.089406 1.96215)
			(end -0.891794 1.96215)
			(stroke
				(width 0.0127)
				(type default)
			)
			(layer "F.SilkS")
		)
		(fp_line
			(start -1.080008 1.952752)
			(end -0.901446 1.952752)
			(stroke
				(width 0.0127)
				(type default)
			)
			(layer "F.SilkS")
		)
		(fp_line
			(start -1.070356 1.9431)
			(end -0.910844 1.9431)
			(stroke
				(width 0.0127)
				(type default)
			)
			(layer "F.SilkS")
		)
		(fp_line
			(start -1.060958 1.933702)
			(end -0.920496 1.933702)
			(stroke
				(width 0.0127)
				(type default)
			)
			(layer "F.SilkS")
		)
		(fp_line
			(start -1.051306 1.92405)
			(end -0.929894 1.92405)
			(stroke
				(width 0.0127)
				(type default)
			)
			(layer "F.SilkS")
		)
		(fp_line
			(start -1.041908 1.914652)
			(end -0.939546 1.914652)
			(stroke
				(width 0.0127)
				(type default)
			)
			(layer "F.SilkS")
		)
		(fp_line
			(start -1.032256 1.905)
			(end -0.948944 1.905)
			(stroke
				(width 0.0127)
				(type default)
			)
			(layer "F.SilkS")
		)
		(fp_line
			(start -1.022858 1.895602)
			(end -0.958596 1.895602)
			(stroke
				(width 0.0127)
				(type default)
			)
			(layer "F.SilkS")
		)
		(fp_line
			(start -1.013206 1.88595)
			(end -0.967994 1.88595)
			(stroke
				(width 0.0127)
				(type default)
			)
			(layer "F.SilkS")
		)
		(fp_line
			(start -1.7526 1.8796)
			(end -1.7526 0.9906)
			(stroke
				(width 0.3302)
				(type default)
			)
			(layer "F.SilkS")
		)
		(fp_line
			(start -0.635 1.8796)
			(end -1.7526 1.8796)
			(stroke
				(width 0.3302)
				(type default)
			)
			(layer "F.SilkS")
		)
		(fp_line
			(start -1.003808 1.876552)
			(end -0.977646 1.876552)
			(stroke
				(width 0.0127)
				(type default)
			)
			(layer "F.SilkS")
		)
		(fp_line
			(start -0.994156 1.8669)
			(end -0.987044 1.8669)
			(stroke
				(width 0.0127)
				(type default)
			)
			(layer "F.SilkS")
		)
		(fp_line
			(start -0.9906 1.86309)
			(end -0.701294 2.15265)
			(stroke
				(width 0.0127)
				(type default)
			)
			(layer "F.SilkS")
		)
		(fp_line
			(start -1.651 1.778)
			(end 1.651 1.778)
			(stroke
				(width 0.1524)
				(type default)
			)
			(layer "F.SilkS")
		)
		(fp_line
			(start 1.651 1.778)
			(end 1.651 -1.778)
			(stroke
				(width 0.1524)
				(type default)
			)
			(layer "F.SilkS")
		)
		(fp_line
			(start -1.651 -1.778)
			(end -1.651 1.778)
			(stroke
				(width 0.1524)
				(type default)
			)
			(layer "F.SilkS")
		)
		(fp_line
			(start 1.651 -1.778)
			(end -1.651 -1.778)
			(stroke
				(width 0.1524)
				(type default)
			)
			(layer "F.SilkS")
		)
		(fp_poly
			(pts
				(xy -1.285748 2.159) (xy -1.285748 1.8796) (xy -1.778 1.8796) (xy -1.778 -1.8796) (xy 1.778 -1.8796)
				(xy 1.778 1.8796) (xy -0.694944 1.8796) (xy -0.694944 2.159)
			)
			(stroke
				(width 0)
				(type default)
			)
			(fill no)
			(layer "F.CrtYd")
		)
		(fp_poly
			(pts
				(xy -1.285748 2.159) (xy -1.285748 1.8796) (xy -1.778 1.8796) (xy -1.778 -1.8796) (xy 1.778 -1.8796)
				(xy 1.778 1.8796) (xy -0.694944 1.8796) (xy -0.694944 2.159)
			)
			(stroke
				(width 0)
				(type default)
			)
			(fill no)
			(layer "F.Fab")
		)
		(pad "1" smd rect
			(at -0.98425 0.9525 270)
			(size 0.762 1.143)
			(layers "F.Cu" "F.Mask" "F.Paste")
			(net "FLT_HDD14_B")
		)
		(pad "2" smd rect
			(at 0.98425 0.9525 270)
			(size 0.762 1.143)
			(layers "F.Cu" "F.Mask" "F.Paste")
			(net "GND")
		)
		(pad "3" smd rect
			(at 0 -0.9525 270)
			(size 0.762 1.143)
			(layers "F.Cu" "F.Mask" "F.Paste")
			(net "DRIVE_ACT_14")
		)
	)
	(footprint ""
		(layer "F.Cu")
		(at 32.86506 -366.964214 -90)
		(property "Reference" "C199"
			(at 0 0 270)
			(layer "F.SilkS")
			(hide yes)
			(effects
				(font
					(size 1.27 1.27)
				)
			)
		)
		(property "Value" "SCD01U50V2KX-1GP"
			(at 1.1811 -2.7051 270)
			(unlocked yes)
			(layer "F.Fab")
			(hide yes)
			(effects
				(font
					(size 1.016 1.016)
					(thickness 0.1524)
				)
			)
		)
		(property "Device Type" "C402H22"
			(at 1.1811 -4.2291 270)
			(unlocked yes)
			(layer "F.Fab")
			(hide yes)
			(effects
				(font
					(size 1.016 1.016)
					(thickness 0.1524)
				)
			)
		)
		(duplicate_pad_numbers_are_jumpers no)
		(fp_rect
			(start -0.4318 0.9525)
			(end 0.4318 -0.9525)
			(stroke
				(width 0)
				(type default)
			)
			(fill no)
			(layer "F.CrtYd")
		)
		(fp_rect
			(start -0.4318 0.9525)
			(end 0.4318 -0.9525)
			(stroke
				(width 0)
				(type default)
			)
			(fill no)
			(layer "F.Fab")
		)
		(pad "1" smd custom
			(at 0 -0.4445 270)
			(size 0.1524 0.1524)
			(layers "F.Cu" "F.Mask" "F.Paste")
			(net "SAS2X28_DRIVE_RX_P_A6")
			(options
				(clearance outline)
				(anchor circle)
			)
			(primitives
				(gr_poly
					(pts
						(arc
							(start 0.3048 -0.2032)
							(mid 0.275042 -0.275042)
							(end 0.2032 -0.3048)
						)
						(arc
							(start -0.2032 -0.3048)
							(mid -0.275042 -0.275042)
							(end -0.3048 -0.2032)
						)
						(arc
							(start -0.3048 0.2032)
							(mid -0.275042 0.275042)
							(end -0.2032 0.3048)
						)
						(arc
							(start 0.2032 0.3048)
							(mid 0.275042 0.275042)
							(end 0.3048 0.2032)
						)
					)
					(width 0)
					(fill yes)
				)
			)
		)
		(pad "2" smd custom
			(at 0 0.4445 270)
			(size 0.1524 0.1524)
			(layers "F.Cu" "F.Mask" "F.Paste")
			(net "SAS2X28_A_HDD6_RX_+")
			(options
				(clearance outline)
				(anchor circle)
			)
			(primitives
				(gr_poly
					(pts
						(arc
							(start 0.3048 -0.2032)
							(mid 0.275042 -0.275042)
							(end 0.2032 -0.3048)
						)
						(arc
							(start -0.2032 -0.3048)
							(mid -0.275042 -0.275042)
							(end -0.3048 -0.2032)
						)
						(arc
							(start -0.3048 0.2032)
							(mid -0.275042 0.275042)
							(end -0.2032 0.3048)
						)
						(arc
							(start 0.2032 0.3048)
							(mid 0.275042 0.275042)
							(end 0.3048 0.2032)
						)
					)
					(width 0)
					(fill yes)
				)
			)
		)
	)
	(footprint ""
		(layer "F.Cu")
		(at 198.114412 -77.831696)
		(property "Reference" "C165"
			(at 0 0 0)
			(layer "F.SilkS")
			(hide yes)
			(effects
				(font
					(size 1.27 1.27)
				)
			)
		)
		(property "Value" "SCD1U10V2KX-5GP"
			(at 1.1811 -2.7051 0)
			(unlocked yes)
			(layer "F.Fab")
			(hide yes)
			(effects
				(font
					(size 1.016 1.016)
					(thickness 0.1524)
				)
			)
		)
		(property "Device Type" "C402H22"
			(at 1.1811 -4.2291 0)
			(unlocked yes)
			(layer "F.Fab")
			(hide yes)
			(effects
				(font
					(size 1.016 1.016)
					(thickness 0.1524)
				)
			)
		)
		(duplicate_pad_numbers_are_jumpers no)
		(fp_rect
			(start -0.4318 0.9525)
			(end 0.4318 -0.9525)
			(stroke
				(width 0)
				(type default)
			)
			(fill no)
			(layer "F.CrtYd")
		)
		(fp_rect
			(start -0.4318 0.9525)
			(end 0.4318 -0.9525)
			(stroke
				(width 0)
				(type default)
			)
			(fill no)
			(layer "F.Fab")
		)
		(pad "1" smd custom
			(at 0 -0.4445)
			(size 0.1524 0.1524)
			(layers "F.Cu" "F.Mask" "F.Paste")
			(net "P3V3")
			(options
				(clearance outline)
				(anchor circle)
			)
			(primitives
				(gr_poly
					(pts
						(arc
							(start 0.3048 -0.2032)
							(mid 0.275042 -0.275042)
							(end 0.2032 -0.3048)
						)
						(arc
							(start -0.2032 -0.3048)
							(mid -0.275042 -0.275042)
							(end -0.3048 -0.2032)
						)
						(arc
							(start -0.3048 0.2032)
							(mid -0.275042 0.275042)
							(end -0.2032 0.3048)
						)
						(arc
							(start 0.2032 0.3048)
							(mid 0.275042 0.275042)
							(end 0.3048 0.2032)
						)
					)
					(width 0)
					(fill yes)
				)
			)
		)
		(pad "2" smd custom
			(at 0 0.4445)
			(size 0.1524 0.1524)
			(layers "F.Cu" "F.Mask" "F.Paste")
			(net "GND")
			(options
				(clearance outline)
				(anchor circle)
			)
			(primitives
				(gr_poly
					(pts
						(arc
							(start 0.3048 -0.2032)
							(mid 0.275042 -0.275042)
							(end 0.2032 -0.3048)
						)
						(arc
							(start -0.2032 -0.3048)
							(mid -0.275042 -0.275042)
							(end -0.3048 -0.2032)
						)
						(arc
							(start -0.3048 0.2032)
							(mid -0.275042 0.275042)
							(end -0.2032 0.3048)
						)
						(arc
							(start 0.2032 0.3048)
							(mid 0.275042 0.275042)
							(end 0.3048 0.2032)
						)
					)
					(width 0)
					(fill yes)
				)
			)
		)
	)
)
